(kicad_pcb
	(version 20260206)
	(generator "pcbnew")
	(generator_version "10.0")
	(general
		(thickness 1.6)
		(legacy_teardrops no)
	)
	(paper "A4")
	(title_block
		(title "04192023_DAF0TMB3IC0_F0TG_MB_C_brd_V02_OCP.brd")
		(comment 1 "Grand Teton / footprints 3969-3974 of 8354")
	)
	(layers
		(0 "F.Cu" signal "TOP")
		(4 "In1.Cu" signal "GND")
		(6 "In2.Cu" signal "IN1")
		(8 "In3.Cu" signal "GND1")
		(10 "In4.Cu" signal "IN2")
		(12 "In5.Cu" signal "GND2")
		(14 "In6.Cu" signal "IN3")
		(16 "In7.Cu" signal "GND3")
		(18 "In8.Cu" signal "VCC")
		(20 "In9.Cu" signal "VCC1")
		(22 "In10.Cu" signal "GND4")
		(24 "In11.Cu" signal "IN4")
		(26 "In12.Cu" signal "GND5")
		(28 "In13.Cu" signal "IN5")
		(30 "In14.Cu" signal "GND6")
		(32 "In15.Cu" signal "IN6")
		(34 "In16.Cu" signal "GND7")
		(2 "B.Cu" signal "BOTTOM")
		(9 "F.Adhes" user "F.Adhesive")
		(11 "B.Adhes" user "B.Adhesive")
		(13 "F.Paste" user "Package Geometry/Pastemask Top")
		(15 "B.Paste" user "Package Geometry/Pastemask Bottom")
		(5 "F.SilkS" user "Ref Des/Silkscreen Top")
		(7 "B.SilkS" user "Ref Des/Silkscreen Bottom")
		(1 "F.Mask" user "Board Geometry/Soldermask Top")
		(3 "B.Mask" user "Board Geometry/Soldermask Bottom")
		(17 "Dwgs.User" user "User.Drawings")
		(19 "Cmts.User" user "User.Comments")
		(21 "Eco1.User" user "User.Eco1")
		(23 "Eco2.User" user "User.Eco2")
		(25 "Edge.Cuts" user "Board Geometry/Outline")
		(27 "Margin" user)
		(31 "F.CrtYd" user "Package Geometry/Place Bound Top")
		(29 "B.CrtYd" user "Package Geometry/Place Bound Bottom")
		(35 "F.Fab" user "Ref Des/Assembly Top")
		(33 "B.Fab" user "Ref Des/Assembly Bottom")
	)
	(footprint ""
		(layer "F.Cu")
		(at 298.878498 -424.78833 -90)
		(property "Reference" "U11"
			(at 0.413766 3.240532 90)
			(unlocked yes)
			(layer "F.SilkS")
			(effects
				(font
					(size 0.7874 0.5842)
					(thickness 0.1524)
				)
				(justify left)
			)
		)
		(property "Value" ""
			(at 0 0 270)
			(layer "F.Fab")
			(effects
				(font
					(size 1.27 1.27)
				)
			)
		)
		(duplicate_pad_numbers_are_jumpers no)
		(fp_line
			(start -1.8288 2.500122)
			(end 1.8288 2.500122)
			(stroke
				(width 0.1524)
				(type default)
			)
			(layer "F.SilkS")
		)
		(fp_line
			(start 1.8288 2.500122)
			(end 1.8288 -2.500122)
			(stroke
				(width 0.1524)
				(type default)
			)
			(layer "F.SilkS")
		)
		(fp_line
			(start 0 -1.4224)
			(end -1.077722 -2.500122)
			(stroke
				(width 0.1524)
				(type default)
			)
			(layer "F.SilkS")
		)
		(fp_line
			(start -1.8288 -2.500122)
			(end -1.8288 2.500122)
			(stroke
				(width 0.1524)
				(type default)
			)
			(layer "F.SilkS")
		)
		(fp_line
			(start -1.077722 -2.500122)
			(end -1.8288 -2.500122)
			(stroke
				(width 0.1524)
				(type default)
			)
			(layer "F.SilkS")
		)
		(fp_line
			(start 1.077722 -2.500122)
			(end 0 -1.4224)
			(stroke
				(width 0.1524)
				(type default)
			)
			(layer "F.SilkS")
		)
		(fp_line
			(start 1.8288 -2.500122)
			(end 1.077722 -2.500122)
			(stroke
				(width 0.1524)
				(type default)
			)
			(layer "F.SilkS")
		)
		(fp_poly
			(pts
				(xy -4.41198 -2.683002) (xy -4.41198 -1.667002) (xy -3.39598 -2.175002)
			)
			(stroke
				(width 0)
				(type default)
			)
			(fill yes)
			(layer "F.SilkS")
		)
		(fp_line
			(start -1.999996 2.500122)
			(end 1.999996 2.500122)
			(stroke
				(width 0.1)
				(type default)
			)
			(layer "F.Fab")
		)
		(fp_line
			(start 1.999996 2.500122)
			(end 1.999996 -2.500122)
			(stroke
				(width 0.1)
				(type default)
			)
			(layer "F.Fab")
		)
		(fp_line
			(start -1.999996 -2.500122)
			(end -1.999996 2.500122)
			(stroke
				(width 0.1)
				(type default)
			)
			(layer "F.Fab")
		)
		(fp_line
			(start 1.999996 -2.500122)
			(end -1.999996 -2.500122)
			(stroke
				(width 0.1)
				(type default)
			)
			(layer "F.Fab")
		)
		(fp_poly
			(pts
				(xy -4.5085 -2.413) (xy -4.5085 -1.397) (xy -3.4925 -1.905)
			)
			(stroke
				(width 0)
				(type default)
			)
			(fill yes)
			(layer "F.Fab")
		)
		(pad "1" smd rect
			(at -2.599944 -1.905 180)
			(size 0.889 1.27)
			(layers "F.Cu" "F.Mask" "F.Paste")
			(net "Net_10847")
		)
		(pad "2" smd rect
			(at -2.599944 -0.635 180)
			(size 0.889 1.27)
			(layers "F.Cu" "F.Mask" "F.Paste")
			(net "Net_10846")
		)
		(pad "3" smd rect
			(at -2.599944 0.635 180)
			(size 0.889 1.27)
			(layers "F.Cu" "F.Mask" "F.Paste")
			(net "U11_E2")
		)
		(pad "4" smd rect
			(at -2.599944 1.905 180)
			(size 0.889 1.27)
			(layers "F.Cu" "F.Mask" "F.Paste")
			(net "GND")
		)
		(pad "5" smd rect
			(at 2.599944 1.905 180)
			(size 0.889 1.27)
			(layers "F.Cu" "F.Mask" "F.Paste")
			(net "SMB_RT_CPU0_P0_ROM_SDA")
		)
		(pad "6" smd rect
			(at 2.599944 0.635 180)
			(size 0.889 1.27)
			(layers "F.Cu" "F.Mask" "F.Paste")
			(net "SMB_RT_CPU0_P0_ROM_SCL")
		)
		(pad "7" smd rect
			(at 2.599944 -0.635 180)
			(size 0.889 1.27)
			(layers "F.Cu" "F.Mask" "F.Paste")
			(net "GND")
		)
		(pad "8" smd rect
			(at 2.599944 -1.905 180)
			(size 0.889 1.27)
			(layers "F.Cu" "F.Mask" "F.Paste")
			(net "P1V8_CPU0_RT_1D")
		)
	)
	(footprint ""
		(layer "F.Cu")
		(at 144.74063 -95.612458)
		(property "Reference" "U245"
			(at -0.08128 1.90119 0)
			(unlocked yes)
			(layer "F.SilkS")
			(effects
				(font
					(size 0.7874 0.5842)
					(thickness 0.1524)
				)
			)
		)
		(property "Value" ""
			(at 0 0 0)
			(layer "F.Fab")
			(effects
				(font
					(size 1.27 1.27)
				)
			)
		)
		(duplicate_pad_numbers_are_jumpers no)
		(fp_line
			(start -1.7272 1.1176)
			(end -1.7272 -1.1176)
			(stroke
				(width 0.1524)
				(type default)
			)
			(layer "F.SilkS")
		)
		(fp_line
			(start -0.254 -1.1176)
			(end -1.7272 -1.1176)
			(stroke
				(width 0.1524)
				(type default)
			)
			(layer "F.SilkS")
		)
		(fp_line
			(start 0 -0.7366)
			(end -0.254 -1.1176)
			(stroke
				(width 0.1524)
				(type default)
			)
			(layer "F.SilkS")
		)
		(fp_line
			(start 0.254 -1.1176)
			(end 0 -0.7366)
			(stroke
				(width 0.1524)
				(type default)
			)
			(layer "F.SilkS")
		)
		(fp_line
			(start 1.7272 -1.1176)
			(end 0.254 -1.1176)
			(stroke
				(width 0.1524)
				(type default)
			)
			(layer "F.SilkS")
		)
		(fp_line
			(start 1.7272 -1.1176)
			(end 1.7272 1.1176)
			(stroke
				(width 0.1524)
				(type default)
			)
			(layer "F.SilkS")
		)
		(fp_line
			(start 1.7272 1.1176)
			(end -1.7272 1.1176)
			(stroke
				(width 0.1524)
				(type default)
			)
			(layer "F.SilkS")
		)
		(fp_poly
			(pts
				(xy -2.7178 -1.030986) (xy -1.9558 -0.649986) (xy -2.7178 -0.268986)
			)
			(stroke
				(width 0)
				(type default)
			)
			(fill yes)
			(layer "F.SilkS")
		)
		(fp_line
			(start -1.5748 -1.1176)
			(end -1.5748 1.1176)
			(stroke
				(width 0.1)
				(type default)
			)
			(layer "F.Fab")
		)
		(fp_line
			(start -1.5748 1.1176)
			(end 1.5748 1.1176)
			(stroke
				(width 0.1)
				(type default)
			)
			(layer "F.Fab")
		)
		(fp_line
			(start 1.5748 -1.1176)
			(end -1.5748 -1.1176)
			(stroke
				(width 0.1)
				(type default)
			)
			(layer "F.Fab")
		)
		(fp_line
			(start 1.5748 1.1176)
			(end 1.5748 -1.1176)
			(stroke
				(width 0.1)
				(type default)
			)
			(layer "F.Fab")
		)
		(fp_poly
			(pts
				(xy -1.9558 -0.649986) (xy -2.7178 -0.268986) (xy -2.7178 -1.030986)
			)
			(stroke
				(width 0)
				(type default)
			)
			(fill yes)
			(layer "F.Fab")
		)
		(pad "1" smd rect
			(at -0.999998 -0.649986 270)
			(size 0.3556 1.1176)
			(layers "F.Cu" "F.Mask" "F.Paste")
			(net "OCP_V3_2_NOT_PRSNT_RBT_ARB_IN")
		)
		(pad "2" smd rect
			(at -0.999998 0 270)
			(size 0.3556 1.1176)
			(layers "F.Cu" "F.Mask" "F.Paste")
			(net "GND")
		)
		(pad "3" smd rect
			(at -0.999998 0.649986 270)
			(size 0.3556 1.1176)
			(layers "F.Cu" "F.Mask" "F.Paste")
			(net "OCP_V3_2_RBT_ARB_IN")
		)
		(pad "4" smd rect
			(at 0.999998 0.649986 270)
			(size 0.3556 1.1176)
			(layers "F.Cu" "F.Mask" "F.Paste")
			(net "OCP_SFF_RBT_ARB_IN_MUX2_R")
		)
		(pad "5" smd rect
			(at 0.999998 0 270)
			(size 0.3556 1.1176)
			(layers "F.Cu" "F.Mask" "F.Paste")
			(net "P3V3_AUX")
		)
		(pad "6" smd rect
			(at 0.999998 -0.649986 270)
			(size 0.3556 1.1176)
			(layers "F.Cu" "F.Mask" "F.Paste")
			(net "OCP_V3_2_PRSNT_ALL_R3_N")
		)
	)
	(footprint ""
		(layer "F.Cu")
		(at 438.056782 -433.49926 90)
		(property "Reference" "R9044"
			(at 0 0 90)
			(layer "F.SilkS")
			(hide yes)
			(effects
				(font
					(size 1.27 1.27)
				)
			)
		)
		(property "Value" ""
			(at 0 0 90)
			(layer "F.Fab")
			(effects
				(font
					(size 1.27 1.27)
				)
			)
		)
		(duplicate_pad_numbers_are_jumpers no)
		(fp_line
			(start 0.7874 -0.4064)
			(end 0.7874 0.4064)
			(stroke
				(width 0.1524)
				(type default)
			)
			(layer "F.SilkS")
		)
		(fp_line
			(start -0.7874 -0.4064)
			(end 0.7874 -0.4064)
			(stroke
				(width 0.1524)
				(type default)
			)
			(layer "F.SilkS")
		)
		(fp_line
			(start 0.7874 0.4064)
			(end -0.7874 0.4064)
			(stroke
				(width 0.1524)
				(type default)
			)
			(layer "F.SilkS")
		)
		(fp_line
			(start -0.7874 0.4064)
			(end -0.7874 -0.4064)
			(stroke
				(width 0.1524)
				(type default)
			)
			(layer "F.SilkS")
		)
		(fp_line
			(start -0.12065 -0.305054)
			(end -0.12065 -0.2794)
			(stroke
				(width 0.1)
				(type default)
			)
			(layer "F.Fab")
		)
		(fp_line
			(start -0.67945 -0.305054)
			(end -0.12065 -0.305054)
			(stroke
				(width 0.1)
				(type default)
			)
			(layer "F.Fab")
		)
		(fp_line
			(start 0.67945 -0.3048)
			(end 0.67945 0.3048)
			(stroke
				(width 0.1)
				(type default)
			)
			(layer "F.Fab")
		)
		(fp_line
			(start 0.12065 -0.3048)
			(end 0.67945 -0.3048)
			(stroke
				(width 0.1)
				(type default)
			)
			(layer "F.Fab")
		)
		(fp_line
			(start 0.12065 -0.2794)
			(end 0.12065 -0.3048)
			(stroke
				(width 0.1)
				(type default)
			)
			(layer "F.Fab")
		)
		(fp_line
			(start -0.12065 -0.2794)
			(end 0.12065 -0.2794)
			(stroke
				(width 0.1)
				(type default)
			)
			(layer "F.Fab")
		)
		(fp_line
			(start 0.120396 0.2794)
			(end -0.12065 0.2794)
			(stroke
				(width 0.1)
				(type default)
			)
			(layer "F.Fab")
		)
		(fp_line
			(start -0.12065 0.2794)
			(end -0.12065 0.3048)
			(stroke
				(width 0.1)
				(type default)
			)
			(layer "F.Fab")
		)
		(fp_line
			(start 0.67945 0.3048)
			(end 0.120396 0.3048)
			(stroke
				(width 0.1)
				(type default)
			)
			(layer "F.Fab")
		)
		(fp_line
			(start 0.120396 0.3048)
			(end 0.120396 0.2794)
			(stroke
				(width 0.1)
				(type default)
			)
			(layer "F.Fab")
		)
		(fp_line
			(start -0.12065 0.3048)
			(end -0.67945 0.3048)
			(stroke
				(width 0.1)
				(type default)
			)
			(layer "F.Fab")
		)
		(fp_line
			(start -0.67945 0.3048)
			(end -0.67945 -0.305054)
			(stroke
				(width 0.1)
				(type default)
			)
			(layer "F.Fab")
		)
		(pad "1" smd circle
			(at -0.40005 0 90)
			(size 0 0)
			(layers "F.Cu" "F.Mask" "F.Paste")
			(net "P3V3_AUX")
		)
		(pad "2" smd circle
			(at 0.40005 0 90)
			(size 0 0)
			(layers "F.Cu" "F.Mask" "F.Paste")
			(net "GPU_WP_HW_CTRL_ISO_N")
		)
	)
	(footprint ""
		(layer "F.Cu")
		(at 295.6814 -367.03)
		(property "Reference" "PQ10"
			(at -1.458214 -3.378454 0)
			(unlocked yes)
			(layer "F.SilkS")
			(effects
				(font
					(size 0.7874 0.5842)
					(thickness 0.1524)
				)
				(justify left)
			)
		)
		(property "Value" ""
			(at 0 0 0)
			(layer "F.Fab")
			(effects
				(font
					(size 1.27 1.27)
				)
			)
		)
		(duplicate_pad_numbers_are_jumpers no)
		(fp_line
			(start -1.603248 -1.500124)
			(end 1.603248 -1.500124)
			(stroke
				(width 0.1524)
				(type default)
			)
			(layer "F.SilkS")
		)
		(fp_line
			(start -1.603248 1.500124)
			(end -1.603248 -1.500124)
			(stroke
				(width 0.1524)
				(type default)
			)
			(layer "F.SilkS")
		)
		(fp_line
			(start 1.603248 -1.500124)
			(end 1.603248 1.500124)
			(stroke
				(width 0.1524)
				(type default)
			)
			(layer "F.SilkS")
		)
		(fp_line
			(start 1.603248 1.500124)
			(end -1.603248 1.500124)
			(stroke
				(width 0.1524)
				(type default)
			)
			(layer "F.SilkS")
		)
		(fp_line
			(start -1.249934 -1.169924)
			(end -1.249934 -0.729996)
			(stroke
				(width 0.1)
				(type default)
			)
			(layer "F.Fab")
		)
		(fp_line
			(start -1.249934 -0.729996)
			(end -0.6985 -0.729996)
			(stroke
				(width 0.1)
				(type default)
			)
			(layer "F.Fab")
		)
		(fp_line
			(start -1.249934 0.729996)
			(end -1.249934 1.169924)
			(stroke
				(width 0.1)
				(type default)
			)
			(layer "F.Fab")
		)
		(fp_line
			(start -1.249934 1.169924)
			(end -0.700024 1.169924)
			(stroke
				(width 0.1)
				(type default)
			)
			(layer "F.Fab")
		)
		(fp_line
			(start -0.700024 -1.500124)
			(end -0.700024 -1.169924)
			(stroke
				(width 0.1)
				(type default)
			)
			(layer "F.Fab")
		)
		(fp_line
			(start -0.700024 -1.169924)
			(end -1.249934 -1.169924)
			(stroke
				(width 0.1)
				(type default)
			)
			(layer "F.Fab")
		)
		(fp_line
			(start -0.700024 1.169924)
			(end -0.700024 1.500124)
			(stroke
				(width 0.1)
				(type default)
			)
			(layer "F.Fab")
		)
		(fp_line
			(start -0.700024 1.500124)
			(end 0.700024 1.500124)
			(stroke
				(width 0.1)
				(type default)
			)
			(layer "F.Fab")
		)
		(fp_line
			(start -0.6985 -0.729996)
			(end -0.6985 0.729996)
			(stroke
				(width 0.1)
				(type default)
			)
			(layer "F.Fab")
		)
		(fp_line
			(start -0.6985 0.729996)
			(end -1.249934 0.729996)
			(stroke
				(width 0.1)
				(type default)
			)
			(layer "F.Fab")
		)
		(fp_line
			(start 0.700024 -1.500124)
			(end -0.700024 -1.500124)
			(stroke
				(width 0.1)
				(type default)
			)
			(layer "F.Fab")
		)
		(fp_line
			(start 0.700024 -0.219964)
			(end 0.700024 -1.500124)
			(stroke
				(width 0.1)
				(type default)
			)
			(layer "F.Fab")
		)
		(fp_line
			(start 0.700024 0.219964)
			(end 1.249934 0.219964)
			(stroke
				(width 0.1)
				(type default)
			)
			(layer "F.Fab")
		)
		(fp_line
			(start 0.700024 1.500124)
			(end 0.700024 0.219964)
			(stroke
				(width 0.1)
				(type default)
			)
			(layer "F.Fab")
		)
		(fp_line
			(start 1.249934 -0.219964)
			(end 0.700024 -0.219964)
			(stroke
				(width 0.1)
				(type default)
			)
			(layer "F.Fab")
		)
		(fp_line
			(start 1.249934 0.219964)
			(end 1.249934 -0.219964)
			(stroke
				(width 0.1)
				(type default)
			)
			(layer "F.Fab")
		)
		(fp_rect
			(start -0.700024 1.500124)
			(end 0.700024 -1.500124)
			(stroke
				(width 0)
				(type default)
			)
			(fill no)
			(layer "F.Fab")
		)
		(pad "D" smd rect
			(at 0.999998 0 270)
			(size 0.8128 0.9144)
			(layers "F.Cu" "F.Mask" "F.Paste")
			(net "PVDDCR_CPU1_P0_EN1_ADDR_CFG")
		)
		(pad "G" smd rect
			(at -0.999998 -0.94996 270)
			(size 0.8128 0.9144)
			(layers "F.Cu" "F.Mask" "F.Paste")
			(net "PVDDIO_P0_EN_G")
		)
		(pad "S" smd rect
			(at -0.999998 0.94996 270)
			(size 0.8128 0.9144)
			(layers "F.Cu" "F.Mask" "F.Paste")
			(net "P3V3_AUX")
		)
	)
	(footprint ""
		(layer "F.Cu")
		(at 19.304 -361.442 90)
		(property "Reference" "PQ16"
			(at -0.01905 -2.928874 90)
			(unlocked yes)
			(layer "F.SilkS")
			(effects
				(font
					(size 0.7874 0.5842)
					(thickness 0.1524)
				)
			)
		)
		(property "Value" ""
			(at 0 0 90)
			(layer "F.Fab")
			(effects
				(font
					(size 1.27 1.27)
				)
			)
		)
		(duplicate_pad_numbers_are_jumpers no)
		(fp_line
			(start -1.949958 -1.610106)
			(end 1.949958 -1.610106)
			(stroke
				(width 0.1524)
				(type default)
			)
			(layer "F.SilkS")
		)
		(fp_line
			(start 1.949958 -1.560068)
			(end 1.949958 1.610106)
			(stroke
				(width 0.1524)
				(type default)
			)
			(layer "F.SilkS")
		)
		(fp_line
			(start 1.949958 1.610106)
			(end -1.949958 1.610106)
			(stroke
				(width 0.1524)
				(type default)
			)
			(layer "F.SilkS")
		)
		(fp_line
			(start -1.949958 1.610106)
			(end -1.949958 -1.610106)
			(stroke
				(width 0.1524)
				(type default)
			)
			(layer "F.SilkS")
		)
		(fp_line
			(start 0.750062 -1.560068)
			(end 0.750062 1.560068)
			(stroke
				(width 0.1)
				(type default)
			)
			(layer "F.Fab")
		)
		(fp_line
			(start -0.750062 -1.560068)
			(end 0.750062 -1.560068)
			(stroke
				(width 0.1)
				(type default)
			)
			(layer "F.Fab")
		)
		(fp_line
			(start 0.750062 1.560068)
			(end -0.750062 1.560068)
			(stroke
				(width 0.1)
				(type default)
			)
			(layer "F.Fab")
		)
		(fp_line
			(start -0.750062 1.560068)
			(end -0.750062 -1.560068)
			(stroke
				(width 0.1)
				(type default)
			)
			(layer "F.Fab")
		)
		(pad "D" smd rect
			(at 1.100074 0)
			(size 1.016 1.4224)
			(layers "F.Cu" "F.Mask" "F.Paste")
			(net "PVDDIO_P1_EN_G")
		)
		(pad "G" smd rect
			(at -1.100074 -0.94996)
			(size 1.016 1.4224)
			(layers "F.Cu" "F.Mask" "F.Paste")
			(net "PVDDIO_P1_EN_R")
		)
		(pad "S" smd rect
			(at -1.100074 0.94996)
			(size 1.016 1.4224)
			(layers "F.Cu" "F.Mask" "F.Paste")
			(net "GND")
		)
	)
	(footprint ""
		(layer "F.Cu")
		(at 118.617746 -52.48148 180)
		(property "Reference" "R6297"
			(at 0 0 180)
			(layer "F.SilkS")
			(hide yes)
			(effects
				(font
					(size 1.27 1.27)
				)
			)
		)
		(property "Value" ""
			(at 0 0 180)
			(layer "F.Fab")
			(effects
				(font
					(size 1.27 1.27)
				)
			)
		)
		(duplicate_pad_numbers_are_jumpers no)
		(fp_line
			(start 0.7874 0.4064)
			(end -0.7874 0.4064)
			(stroke
				(width 0.1524)
				(type default)
			)
			(layer "F.SilkS")
		)
		(fp_line
			(start 0.7874 -0.4064)
			(end 0.7874 0.4064)
			(stroke
				(width 0.1524)
				(type default)
			)
			(layer "F.SilkS")
		)
		(fp_line
			(start -0.7874 0.4064)
			(end -0.7874 -0.4064)
			(stroke
				(width 0.1524)
				(type default)
			)
			(layer "F.SilkS")
		)
		(fp_line
			(start -0.7874 -0.4064)
			(end 0.7874 -0.4064)
			(stroke
				(width 0.1524)
				(type default)
			)
			(layer "F.SilkS")
		)
		(fp_line
			(start 0.67945 0.3048)
			(end 0.120396 0.3048)
			(stroke
				(width 0.1)
				(type default)
			)
			(layer "F.Fab")
		)
		(fp_line
			(start 0.67945 -0.3048)
			(end 0.67945 0.3048)
			(stroke
				(width 0.1)
				(type default)
			)
			(layer "F.Fab")
		)
		(fp_line
			(start 0.12065 -0.2794)
			(end 0.12065 -0.3048)
			(stroke
				(width 0.1)
				(type default)
			)
			(layer "F.Fab")
		)
		(fp_line
			(start 0.12065 -0.3048)
			(end 0.67945 -0.3048)
			(stroke
				(width 0.1)
				(type default)
			)
			(layer "F.Fab")
		)
		(fp_line
			(start 0.120396 0.3048)
			(end 0.120396 0.2794)
			(stroke
				(width 0.1)
				(type default)
			)
			(layer "F.Fab")
		)
		(fp_line
			(start 0.120396 0.2794)
			(end -0.12065 0.2794)
			(stroke
				(width 0.1)
				(type default)
			)
			(layer "F.Fab")
		)
		(fp_line
			(start -0.12065 0.3048)
			(end -0.67945 0.3048)
			(stroke
				(width 0.1)
				(type default)
			)
			(layer "F.Fab")
		)
		(fp_line
			(start -0.12065 0.2794)
			(end -0.12065 0.3048)
			(stroke
				(width 0.1)
				(type default)
			)
			(layer "F.Fab")
		)
		(fp_line
			(start -0.12065 -0.2794)
			(end 0.12065 -0.2794)
			(stroke
				(width 0.1)
				(type default)
			)
			(layer "F.Fab")
		)
		(fp_line
			(start -0.12065 -0.305054)
			(end -0.12065 -0.2794)
			(stroke
				(width 0.1)
				(type default)
			)
			(layer "F.Fab")
		)
		(fp_line
			(start -0.67945 0.3048)
			(end -0.67945 -0.305054)
			(stroke
				(width 0.1)
				(type default)
			)
			(layer "F.Fab")
		)
		(fp_line
			(start -0.67945 -0.305054)
			(end -0.12065 -0.305054)
			(stroke
				(width 0.1)
				(type default)
			)
			(layer "F.Fab")
		)
		(pad "1" smd circle
			(at -0.40005 0 180)
			(size 0 0)
			(layers "F.Cu" "F.Mask" "F.Paste")
			(net "P3V3_AUX")
		)
		(pad "2" smd circle
			(at 0.40005 0 180)
			(size 0 0)
			(layers "F.Cu" "F.Mask" "F.Paste")
			(net "USB_HUB2_TI_OVERCCUR4")
		)
	)
)
